(kicad_pcb
	(version 20260206)
	(generator "pcbnew")
	(generator_version "10.0")
	(general
		(thickness 1.6)
		(legacy_teardrops no)
	)
	(paper "A4")
	(title_block
		(title "panther-plus-userver — 13130-1b_20150205.brd")
		(comment 1 "Honey Badger (Wiwynn) / footprints 598-605 of 1509")
	)
	(layers
		(0 "F.Cu" signal "TOP")
		(4 "In1.Cu" signal "L2")
		(6 "In2.Cu" signal "L3")
		(8 "In3.Cu" signal "L4")
		(10 "In4.Cu" signal "L5")
		(12 "In5.Cu" signal "L6")
		(14 "In6.Cu" signal "L7")
		(16 "In7.Cu" signal "L8")
		(18 "In8.Cu" signal "L9")
		(20 "In9.Cu" signal "L10")
		(22 "In10.Cu" signal "L11")
		(2 "B.Cu" signal "BOTTOM")
		(9 "F.Adhes" user "F.Adhesive")
		(11 "B.Adhes" user "B.Adhesive")
		(13 "F.Paste" user "Package Geometry/Pastemask Top")
		(15 "B.Paste" user "Package Geometry/Pastemask Bottom")
		(5 "F.SilkS" user "Ref Des/Silkscreen Top")
		(7 "B.SilkS" user "Ref Des/Silkscreen Bottom")
		(1 "F.Mask" user "Board Geometry/Soldermask Top")
		(3 "B.Mask" user "Board Geometry/Soldermask Bottom")
		(17 "Dwgs.User" user "User.Drawings")
		(19 "Cmts.User" user "User.Comments")
		(21 "Eco1.User" user "User.Eco1")
		(23 "Eco2.User" user "User.Eco2")
		(25 "Edge.Cuts" user "Board Geometry/Outline")
		(27 "Margin" user)
		(31 "F.CrtYd" user "Package Geometry/Place Bound Top")
		(29 "B.CrtYd" user "Package Geometry/Place Bound Bottom")
		(35 "F.Fab" user "Ref Des/Assembly Top")
		(33 "B.Fab" user "Ref Des/Assembly Bottom")
	)
	(footprint ""
		(layer "F.Cu")
		(at 116.967 -41.1988 90)
		(property "Reference" "C161"
			(at 0 0 90)
			(layer "F.SilkS")
			(hide yes)
			(effects
				(font
					(size 1.27 1.27)
				)
			)
		)
		(property "Value" "SC22U6D3V5MX-2GP"
			(at -0.0762 -6.1214 90)
			(unlocked yes)
			(layer "F.Fab")
			(hide yes)
			(effects
				(font
					(size 1.016 1.016)
					(thickness 0.1524)
				)
			)
		)
		(property "Device Type" "C805H58"
			(at -0.0762 -8.1534 90)
			(unlocked yes)
			(layer "F.Fab")
			(hide yes)
			(effects
				(font
					(size 1.016 1.016)
					(thickness 0.1524)
				)
			)
		)
		(duplicate_pad_numbers_are_jumpers no)
		(fp_line
			(start 0.6096 0)
			(end -0.6096 0)
			(stroke
				(width 0.3048)
				(type default)
			)
			(layer "F.SilkS")
		)
		(fp_poly
			(pts
				(xy -0.9017 1.4351) (xy 0.9017 1.4351) (xy 0.9017 -1.4351) (xy -0.9017 -1.4351)
			)
			(stroke
				(width 0)
				(type default)
			)
			(fill no)
			(layer "F.CrtYd")
		)
		(fp_poly
			(pts
				(xy 0.9271 1.4351) (xy 0.9271 -1.4351) (xy -0.8763 -1.4351) (xy -0.8763 1.4351)
			)
			(stroke
				(width 0)
				(type default)
			)
			(fill no)
			(layer "F.Fab")
		)
		(pad "1" smd rect
			(at 0 -0.8382 90)
			(size 1.5494 0.9398)
			(layers "F.Cu" "F.Mask" "F.Paste")
			(net "PVCCP")
		)
		(pad "2" smd rect
			(at 0 0.8382 90)
			(size 1.5494 0.9398)
			(layers "F.Cu" "F.Mask" "F.Paste")
			(net "GND")
		)
	)
	(footprint ""
		(layer "F.Cu")
		(at 20.3708 -67.183 180)
		(property "Reference" "PR17"
			(at 0 0 180)
			(layer "F.SilkS")
			(hide yes)
			(effects
				(font
					(size 1.27 1.27)
				)
			)
		)
		(property "Value" "11KR2F-L-GP"
			(at 1.7907 -1.1176 180)
			(unlocked yes)
			(layer "F.Fab")
			(hide yes)
			(effects
				(font
					(size 1.016 1.016)
					(thickness 0.1524)
				)
			)
		)
		(property "Device Type" "R402H16"
			(at 1.7907 -2.6416 180)
			(unlocked yes)
			(layer "F.Fab")
			(hide yes)
			(effects
				(font
					(size 1.016 1.016)
					(thickness 0.1524)
				)
			)
		)
		(duplicate_pad_numbers_are_jumpers no)
		(fp_rect
			(start -0.381 0.8382)
			(end 0.381 -0.8382)
			(stroke
				(width 0)
				(type default)
			)
			(fill no)
			(layer "F.CrtYd")
		)
		(fp_rect
			(start -0.381 0.8382)
			(end 0.381 -0.8382)
			(stroke
				(width 0)
				(type default)
			)
			(fill no)
			(layer "F.Fab")
		)
		(pad "1" smd custom
			(at 0 -0.4318 180)
			(size 0.127 0.127)
			(layers "F.Cu" "F.Mask" "F.Paste")
			(net "VR_PVNN_ISUMN")
			(options
				(clearance outline)
				(anchor circle)
			)
			(primitives
				(gr_poly
					(pts
						(arc
							(start -0.2032 -0.2794)
							(mid -0.239121 -0.264521)
							(end -0.254 -0.2286)
						)
						(arc
							(start -0.254 0.2286)
							(mid -0.239121 0.264521)
							(end -0.2032 0.2794)
						)
						(arc
							(start 0.2032 0.2794)
							(mid 0.239121 0.264521)
							(end 0.254 0.2286)
						)
						(arc
							(start 0.254 -0.2286)
							(mid 0.239121 -0.264521)
							(end 0.2032 -0.2794)
						)
					)
					(width 0)
					(fill yes)
				)
			)
		)
		(pad "2" smd custom
			(at 0 0.4318 180)
			(size 0.127 0.127)
			(layers "F.Cu" "F.Mask" "F.Paste")
			(net "VR_PVNN_ISUMP")
			(options
				(clearance outline)
				(anchor circle)
			)
			(primitives
				(gr_poly
					(pts
						(arc
							(start -0.2032 -0.2794)
							(mid -0.239121 -0.264521)
							(end -0.254 -0.2286)
						)
						(arc
							(start -0.254 0.2286)
							(mid -0.239121 0.264521)
							(end -0.2032 0.2794)
						)
						(arc
							(start 0.2032 0.2794)
							(mid 0.239121 0.264521)
							(end 0.254 0.2286)
						)
						(arc
							(start 0.254 -0.2286)
							(mid 0.239121 -0.264521)
							(end 0.2032 -0.2794)
						)
					)
					(width 0)
					(fill yes)
				)
			)
		)
	)
	(footprint ""
		(layer "F.Cu")
		(at 149.987 -59.182)
		(property "Reference" "C368"
			(at 0 0 0)
			(layer "F.SilkS")
			(hide yes)
			(effects
				(font
					(size 1.27 1.27)
				)
			)
		)
		(property "Value" "SC47U6D3V5MX-1-GP"
			(at 0 -4.9022 0)
			(unlocked yes)
			(layer "F.Fab")
			(hide yes)
			(effects
				(font
					(size 1.016 1.016)
					(thickness 0.1524)
				)
			)
		)
		(property "Device Type" "C805H54"
			(at 0 -6.8072 0)
			(unlocked yes)
			(layer "F.Fab")
			(hide yes)
			(effects
				(font
					(size 1.016 1.016)
					(thickness 0.1524)
				)
			)
		)
		(duplicate_pad_numbers_are_jumpers no)
		(fp_line
			(start 0.6096 0)
			(end -0.6096 0)
			(stroke
				(width 0.3048)
				(type default)
			)
			(layer "F.SilkS")
		)
		(fp_poly
			(pts
				(xy -0.9017 1.4351) (xy 0.9017 1.4351) (xy 0.9017 -1.4351) (xy -0.9017 -1.4351)
			)
			(stroke
				(width 0)
				(type default)
			)
			(fill no)
			(layer "F.CrtYd")
		)
		(fp_poly
			(pts
				(xy 0.9017 1.4351) (xy 0.9017 -1.4351) (xy -0.9017 -1.4351) (xy -0.9017 1.4351)
			)
			(stroke
				(width 0)
				(type default)
			)
			(fill no)
			(layer "F.Fab")
		)
		(pad "1" smd rect
			(at 0 -0.8382)
			(size 1.5494 0.9398)
			(layers "F.Cu" "F.Mask" "F.Paste")
			(net "PV_VDDR")
		)
		(pad "2" smd rect
			(at 0 0.8382)
			(size 1.5494 0.9398)
			(layers "F.Cu" "F.Mask" "F.Paste")
			(net "GND")
		)
	)
	(footprint ""
		(layer "F.Cu")
		(at 182.118 -17.653 180)
		(property "Reference" "PC115"
			(at 0 0 180)
			(layer "F.SilkS")
			(hide yes)
			(effects
				(font
					(size 1.27 1.27)
				)
			)
		)
		(property "Value" "SC1KP50V2KX-1GP"
			(at 1.1811 -2.7051 180)
			(unlocked yes)
			(layer "F.Fab")
			(hide yes)
			(effects
				(font
					(size 1.016 1.016)
					(thickness 0.1524)
				)
			)
		)
		(property "Device Type" "C402H22"
			(at 1.1811 -4.2291 180)
			(unlocked yes)
			(layer "F.Fab")
			(hide yes)
			(effects
				(font
					(size 1.016 1.016)
					(thickness 0.1524)
				)
			)
		)
		(duplicate_pad_numbers_are_jumpers no)
		(fp_rect
			(start -0.381 0.7366)
			(end 0.381 -0.7366)
			(stroke
				(width 0)
				(type default)
			)
			(fill no)
			(layer "F.CrtYd")
		)
		(fp_rect
			(start -0.381 0.7366)
			(end 0.381 -0.7366)
			(stroke
				(width 0)
				(type default)
			)
			(fill no)
			(layer "F.Fab")
		)
		(pad "1" smd custom
			(at 0 -0.4572 180)
			(size 0.1143 0.1143)
			(layers "F.Cu" "F.Mask" "F.Paste")
			(net "PV_VTT_DDR_B_REFIN")
			(options
				(clearance outline)
				(anchor circle)
			)
			(primitives
				(gr_poly
					(pts
						(arc
							(start -0.254 -0.1778)
							(mid -0.239121 -0.213721)
							(end -0.2032 -0.2286)
						)
						(arc
							(start 0.2032 -0.2286)
							(mid 0.239121 -0.213721)
							(end 0.254 -0.1778)
						)
						(arc
							(start 0.254 0.1778)
							(mid 0.239121 0.213721)
							(end 0.2032 0.2286)
						)
						(arc
							(start -0.2032 0.2286)
							(mid -0.239121 0.213721)
							(end -0.254 0.1778)
						)
					)
					(width 0)
					(fill yes)
				)
			)
		)
		(pad "2" smd custom
			(at 0 0.4572 180)
			(size 0.1143 0.1143)
			(layers "F.Cu" "F.Mask" "F.Paste")
			(net "GND")
			(options
				(clearance outline)
				(anchor circle)
			)
			(primitives
				(gr_poly
					(pts
						(arc
							(start -0.254 -0.1778)
							(mid -0.239121 -0.213721)
							(end -0.2032 -0.2286)
						)
						(arc
							(start 0.2032 -0.2286)
							(mid 0.239121 -0.213721)
							(end 0.254 -0.1778)
						)
						(arc
							(start 0.254 0.1778)
							(mid 0.239121 0.213721)
							(end 0.2032 0.2286)
						)
						(arc
							(start -0.2032 0.2286)
							(mid -0.239121 0.213721)
							(end -0.254 0.1778)
						)
					)
					(width 0)
					(fill yes)
				)
			)
		)
	)
	(footprint ""
		(layer "F.Cu")
		(at 185.674 -22.8854)
		(property "Reference" "PR166"
			(at 0 0 0)
			(layer "F.SilkS")
			(hide yes)
			(effects
				(font
					(size 1.27 1.27)
				)
			)
		)
		(property "Value" "0R2J-2-GP"
			(at 0.064008 -3.993896 0)
			(unlocked yes)
			(layer "F.Fab")
			(hide yes)
			(effects
				(font
					(size 1.016 1.016)
					(thickness 0.1524)
				)
			)
		)
		(property "Device Type" "R402H16"
			(at 0.064008 -5.517896 0)
			(unlocked yes)
			(layer "F.Fab")
			(hide yes)
			(effects
				(font
					(size 1.016 1.016)
					(thickness 0.1524)
				)
			)
		)
		(duplicate_pad_numbers_are_jumpers no)
		(fp_rect
			(start -0.381 0.8382)
			(end 0.381 -0.8382)
			(stroke
				(width 0)
				(type default)
			)
			(fill no)
			(layer "F.CrtYd")
		)
		(fp_rect
			(start -0.381 0.8382)
			(end 0.381 -0.8382)
			(stroke
				(width 0)
				(type default)
			)
			(fill no)
			(layer "F.Fab")
		)
		(pad "1" smd custom
			(at 0 -0.4318)
			(size 0.127 0.127)
			(layers "F.Cu" "F.Mask" "F.Paste")
			(net "PVTT_DDR_EN")
			(options
				(clearance outline)
				(anchor circle)
			)
			(primitives
				(gr_poly
					(pts
						(arc
							(start -0.2032 -0.2794)
							(mid -0.239121 -0.264521)
							(end -0.254 -0.2286)
						)
						(arc
							(start -0.254 0.2286)
							(mid -0.239121 0.264521)
							(end -0.2032 0.2794)
						)
						(arc
							(start 0.2032 0.2794)
							(mid 0.239121 0.264521)
							(end 0.254 0.2286)
						)
						(arc
							(start 0.254 -0.2286)
							(mid 0.239121 -0.264521)
							(end 0.2032 -0.2794)
						)
					)
					(width 0)
					(fill yes)
				)
			)
		)
		(pad "2" smd custom
			(at 0 0.4318)
			(size 0.127 0.127)
			(layers "F.Cu" "F.Mask" "F.Paste")
			(net "PV_VTT_DDR_B_EN")
			(options
				(clearance outline)
				(anchor circle)
			)
			(primitives
				(gr_poly
					(pts
						(arc
							(start -0.2032 -0.2794)
							(mid -0.239121 -0.264521)
							(end -0.254 -0.2286)
						)
						(arc
							(start -0.254 0.2286)
							(mid -0.239121 0.264521)
							(end -0.2032 0.2794)
						)
						(arc
							(start 0.2032 0.2794)
							(mid 0.239121 0.264521)
							(end 0.254 0.2286)
						)
						(arc
							(start 0.254 -0.2286)
							(mid 0.239121 -0.264521)
							(end 0.2032 -0.2794)
						)
					)
					(width 0)
					(fill yes)
				)
			)
		)
	)
	(footprint ""
		(layer "F.Cu")
		(at 27.94 -47.879 90)
		(property "Reference" "PR68"
			(at 0 0 90)
			(layer "F.SilkS")
			(hide yes)
			(effects
				(font
					(size 1.27 1.27)
				)
			)
		)
		(property "Value" "2M2R2J-GP"
			(at 1.7907 -1.1176 90)
			(unlocked yes)
			(layer "F.Fab")
			(hide yes)
			(effects
				(font
					(size 1.016 1.016)
					(thickness 0.1524)
				)
			)
		)
		(property "Device Type" "R402H16"
			(at 1.7907 -2.6416 90)
			(unlocked yes)
			(layer "F.Fab")
			(hide yes)
			(effects
				(font
					(size 1.016 1.016)
					(thickness 0.1524)
				)
			)
		)
		(duplicate_pad_numbers_are_jumpers no)
		(fp_rect
			(start -0.381 0.8382)
			(end 0.381 -0.8382)
			(stroke
				(width 0)
				(type default)
			)
			(fill no)
			(layer "F.CrtYd")
		)
		(fp_rect
			(start -0.381 0.8382)
			(end 0.381 -0.8382)
			(stroke
				(width 0)
				(type default)
			)
			(fill no)
			(layer "F.Fab")
		)
		(pad "1" smd custom
			(at 0 -0.4318 90)
			(size 0.127 0.127)
			(layers "F.Cu" "F.Mask" "F.Paste")
			(net "VR_PVCCP_ISUMP")
			(options
				(clearance outline)
				(anchor circle)
			)
			(primitives
				(gr_poly
					(pts
						(arc
							(start -0.2032 -0.2794)
							(mid -0.239121 -0.264521)
							(end -0.254 -0.2286)
						)
						(arc
							(start -0.254 0.2286)
							(mid -0.239121 0.264521)
							(end -0.2032 0.2794)
						)
						(arc
							(start 0.2032 0.2794)
							(mid 0.239121 0.264521)
							(end 0.254 0.2286)
						)
						(arc
							(start 0.254 -0.2286)
							(mid 0.239121 -0.264521)
							(end 0.2032 -0.2794)
						)
					)
					(width 0)
					(fill yes)
				)
			)
		)
		(pad "2" smd custom
			(at 0 0.4318 90)
			(size 0.127 0.127)
			(layers "F.Cu" "F.Mask" "F.Paste")
			(net "GND")
			(options
				(clearance outline)
				(anchor circle)
			)
			(primitives
				(gr_poly
					(pts
						(arc
							(start -0.2032 -0.2794)
							(mid -0.239121 -0.264521)
							(end -0.254 -0.2286)
						)
						(arc
							(start -0.254 0.2286)
							(mid -0.239121 0.264521)
							(end -0.2032 0.2794)
						)
						(arc
							(start 0.2032 0.2794)
							(mid 0.239121 0.264521)
							(end 0.254 0.2286)
						)
						(arc
							(start 0.254 -0.2286)
							(mid 0.239121 -0.264521)
							(end 0.2032 -0.2794)
						)
					)
					(width 0)
					(fill yes)
				)
			)
		)
	)
	(footprint ""
		(layer "F.Cu")
		(at 72.849994 -66.900044 180)
		(property "Reference" "CN1"
			(at 0 0 180)
			(layer "F.SilkS")
			(hide yes)
			(effects
				(font
					(size 1.27 1.27)
				)
			)
		)
		(property "Value" "PIN-CON2-6-GP-U"
			(at -4.9657 1.2954 180)
			(unlocked yes)
			(layer "F.Fab")
			(hide yes)
			(effects
				(font
					(size 1.016 1.016)
					(thickness 0.1524)
				)
			)
		)
		(property "Device Type" "21U-91-03TB22-U"
			(at -4.9657 -0.2286 180)
			(unlocked yes)
			(layer "F.Fab")
			(hide yes)
			(effects
				(font
					(size 1.016 1.016)
					(thickness 0.1524)
				)
			)
		)
		(duplicate_pad_numbers_are_jumpers no)
		(fp_line
			(start 3.937 1.4986)
			(end -3.937 1.4986)
			(stroke
				(width 0.1524)
				(type default)
			)
			(layer "F.SilkS")
		)
		(fp_line
			(start 3.937 -1.4986)
			(end 3.937 1.4986)
			(stroke
				(width 0.1524)
				(type default)
			)
			(layer "F.SilkS")
		)
		(fp_line
			(start -3.937 1.4986)
			(end -3.937 -1.4986)
			(stroke
				(width 0.1524)
				(type default)
			)
			(layer "F.SilkS")
		)
		(fp_line
			(start -3.937 -1.4986)
			(end 3.937 -1.4986)
			(stroke
				(width 0.1524)
				(type default)
			)
			(layer "F.SilkS")
		)
		(fp_circle
			(center 2.54 0)
			(end 1.4732 0)
			(stroke
				(width 0.3048)
				(type default)
			)
			(fill no)
			(layer "F.SilkS")
		)
		(fp_circle
			(center -2.54 0)
			(end -3.6068 0)
			(stroke
				(width 0.3048)
				(type default)
			)
			(fill no)
			(layer "F.SilkS")
		)
		(fp_rect
			(start -3.683 1.2446)
			(end 3.683 -1.2446)
			(stroke
				(width 0)
				(type default)
			)
			(fill no)
			(layer "F.CrtYd")
		)
		(fp_poly
			(pts
				(xy -4.191 1.7526) (xy -4.191 -1.7526) (xy 4.191 -1.7526) (xy 4.191 -0.00635) (xy 3.683 -0.00635)
				(xy 3.683 -1.2446) (xy -3.683 -1.2446) (xy -3.683 1.2446) (xy 3.683 1.2446) (xy 3.683 0.00635) (xy 4.191 0.00635)
				(xy 4.191 1.7526)
			)
			(stroke
				(width 0)
				(type default)
			)
			(fill no)
			(layer "F.CrtYd")
		)
		(fp_rect
			(start -4.191 1.7526)
			(end 4.191 -1.7526)
			(stroke
				(width 0)
				(type default)
			)
			(fill no)
			(layer "F.Fab")
		)
		(pad "1" thru_hole circle
			(at -2.54 0 180)
			(size 1.4224 1.4224)
			(drill 1.016)
			(layers "*.Cu" "*.Mask")
			(remove_unused_layers no)
			(net "DYMMY_NET1")
			(clearance 0.1524)
			(thermal_gap 0.1524)
		)
		(pad "2" thru_hole circle
			(at 2.54 0 180)
			(size 1.4224 1.4224)
			(drill 1.016)
			(layers "*.Cu" "*.Mask")
			(remove_unused_layers no)
			(net "DYMMY_NET1")
			(clearance 0.1524)
			(thermal_gap 0.1524)
		)
	)
	(footprint ""
		(layer "F.Cu")
		(at 29.845 -49.911 90)
		(property "Reference" "PC130"
			(at 0 0 90)
			(layer "F.SilkS")
			(hide yes)
			(effects
				(font
					(size 1.27 1.27)
				)
			)
		)
		(property "Value" "SC10U6D3V5KX-4GP"
			(at 0 -4.9022 90)
			(unlocked yes)
			(layer "F.Fab")
			(hide yes)
			(effects
				(font
					(size 1.016 1.016)
					(thickness 0.1524)
				)
			)
		)
		(property "Device Type" "C805H58"
			(at 0 -6.8072 90)
			(unlocked yes)
			(layer "F.Fab")
			(hide yes)
			(effects
				(font
					(size 1.016 1.016)
					(thickness 0.1524)
				)
			)
		)
		(duplicate_pad_numbers_are_jumpers no)
		(fp_line
			(start 0.6096 0)
			(end -0.6096 0)
			(stroke
				(width 0.3048)
				(type default)
			)
			(layer "F.SilkS")
		)
		(fp_poly
			(pts
				(xy -0.9017 1.4351) (xy 0.9017 1.4351) (xy 0.9017 -1.4351) (xy -0.9017 -1.4351)
			)
			(stroke
				(width 0)
				(type default)
			)
			(fill no)
			(layer "F.CrtYd")
		)
		(fp_poly
			(pts
				(xy 0.9017 1.4351) (xy 0.9017 -1.4351) (xy -0.9017 -1.4351) (xy -0.9017 1.4351)
			)
			(stroke
				(width 0)
				(type default)
			)
			(fill no)
			(layer "F.Fab")
		)
		(pad "1" smd rect
			(at 0 -0.8382 90)
			(size 1.5494 0.9398)
			(layers "F.Cu" "F.Mask" "F.Paste")
			(net "P1V5_STBY_IN")
		)
		(pad "2" smd rect
			(at 0 0.8382 90)
			(size 1.5494 0.9398)
			(layers "F.Cu" "F.Mask" "F.Paste")
			(net "GND")
		)
	)
)
